(kicad_pcb
	(version 20260206)
	(generator "pcbnew")
	(generator_version "10.0")
	(general
		(thickness 1.6)
		(legacy_teardrops no)
	)
	(paper "A4")
	(title_block
		(title "v2-pdb — ms_pdb_v2.brd")
		(comment 1 "Open CloudServer (Microsoft) / footprint 117 of 348 (J25), pads 79-156 of 166")
	)
	(layers
		(0 "F.Cu" signal "TOP")
		(4 "In1.Cu" signal "GND")
		(6 "In2.Cu" signal "IN1")
		(8 "In3.Cu" signal "VCC")
		(10 "In4.Cu" signal "VCC1")
		(12 "In5.Cu" signal "IN2")
		(14 "In6.Cu" signal "GND1")
		(2 "B.Cu" signal "BOTTOM")
		(9 "F.Adhes" user "F.Adhesive")
		(11 "B.Adhes" user "B.Adhesive")
		(13 "F.Paste" user "Package Geometry/Pastemask Top")
		(15 "B.Paste" user "Package Geometry/Pastemask Bottom")
		(5 "F.SilkS" user "Ref Des/Silkscreen Top")
		(7 "B.SilkS" user "Ref Des/Silkscreen Bottom")
		(1 "F.Mask" user "Board Geometry/Soldermask Top")
		(3 "B.Mask" user "Board Geometry/Soldermask Bottom")
		(17 "Dwgs.User" user "User.Drawings")
		(19 "Cmts.User" user "User.Comments")
		(21 "Eco1.User" user "User.Eco1")
		(23 "Eco2.User" user "User.Eco2")
		(25 "Edge.Cuts" user "Board Geometry/Outline")
		(27 "Margin" user)
		(31 "F.CrtYd" user "Package Geometry/Place Bound Top")
		(29 "B.CrtYd" user "Package Geometry/Place Bound Bottom")
		(35 "F.Fab" user "Ref Des/Assembly Top")
		(33 "B.Fab" user "Ref Des/Assembly Bottom")
	)
	(footprint ""
		(layer "F.Cu")
		(at 6.449822 -352.669856)
		(property "Reference" "J25"
			(at 6.653784 1.81356 90)
			(unlocked yes)
			(layer "F.SilkS")
			(effects
				(font
					(size 0.7874 0.5842)
					(thickness 0.1524)
				)
				(justify left)
			)
		)
		(property "Value" ""
			(at 0 0 0)
			(layer "F.Fab")
			(effects
				(font
					(size 1.27 1.27)
				)
			)
		)
		(duplicate_pad_numbers_are_jumpers no)
		(pad "A77" thru_hole circle
			(at 0 78.000098 270)
			(size 1.016 1.016)
			(drill 0.7112)
			(layers "*.Cu" "*.Mask")
			(remove_unused_layers no)
			(net "T7_BLAD4_RXD")
			(clearance 0.1016)
			(thermal_gap 0.1016)
		)
		(pad "A78" thru_hole circle
			(at 1.999996 79.000096 270)
			(size 1.016 1.016)
			(drill 0.7112)
			(layers "*.Cu" "*.Mask")
			(remove_unused_layers no)
			(net "T7_BLAD4_TXD")
			(clearance 0.1016)
			(thermal_gap 0.1016)
		)
		(pad "A79" thru_hole circle
			(at 0 80.000094 270)
			(size 1.016 1.016)
			(drill 0.7112)
			(layers "*.Cu" "*.Mask")
			(remove_unused_layers no)
			(net "GND")
			(clearance 0.1016)
			(thermal_gap 0.1016)
		)
		(pad "A80" thru_hole circle
			(at 1.999996 81.000092 270)
			(size 1.016 1.016)
			(drill 0.7112)
			(layers "*.Cu" "*.Mask")
			(remove_unused_layers no)
			(net "PSU_ALERT_N")
			(clearance 0.1016)
			(thermal_gap 0.1016)
		)
		(pad "A81" thru_hole circle
			(at 0 82.00009 270)
			(size 1.016 1.016)
			(drill 0.7112)
			(layers "*.Cu" "*.Mask")
			(remove_unused_layers no)
			(net "T5_BLAD1_EN")
			(clearance 0.1016)
			(thermal_gap 0.1016)
		)
		(pad "A82" thru_hole circle
			(at 1.999996 83.000088 270)
			(size 1.016 1.016)
			(drill 0.7112)
			(layers "*.Cu" "*.Mask")
			(remove_unused_layers no)
			(net "TP_T5_BLAD2_EN")
			(clearance 0.1016)
			(thermal_gap 0.1016)
		)
		(pad "B1" thru_hole circle
			(at -2.499868 0 270)
			(size 1.016 1.016)
			(drill 0.7112)
			(layers "*.Cu" "*.Mask")
			(remove_unused_layers no)
			(net "GND")
			(clearance 0.1016)
			(thermal_gap 0.1016)
		)
		(pad "B2" thru_hole circle
			(at -4.499864 0.999998 270)
			(size 1.016 1.016)
			(drill 0.7112)
			(layers "*.Cu" "*.Mask")
			(remove_unused_layers no)
			(net "LAN2_P1_P")
			(clearance 0.1016)
			(thermal_gap 0.1016)
		)
		(pad "B3" thru_hole circle
			(at -2.499868 1.999996 270)
			(size 1.016 1.016)
			(drill 0.7112)
			(layers "*.Cu" "*.Mask")
			(remove_unused_layers no)
			(net "LAN2_P1_N")
			(clearance 0.1016)
			(thermal_gap 0.1016)
		)
		(pad "B4" thru_hole circle
			(at -4.499864 2.999994 270)
			(size 1.016 1.016)
			(drill 0.7112)
			(layers "*.Cu" "*.Mask")
			(remove_unused_layers no)
			(net "GND")
			(clearance 0.1016)
			(thermal_gap 0.1016)
		)
		(pad "B5" thru_hole circle
			(at -2.499868 3.999992 270)
			(size 1.016 1.016)
			(drill 0.7112)
			(layers "*.Cu" "*.Mask")
			(remove_unused_layers no)
			(net "LAN2_P2_P")
			(clearance 0.1016)
			(thermal_gap 0.1016)
		)
		(pad "B6" thru_hole circle
			(at -4.499864 4.99999 270)
			(size 1.016 1.016)
			(drill 0.7112)
			(layers "*.Cu" "*.Mask")
			(remove_unused_layers no)
			(net "LAN2_P2_N")
			(clearance 0.1016)
			(thermal_gap 0.1016)
		)
		(pad "B7" thru_hole circle
			(at -2.499868 5.999988 270)
			(size 1.016 1.016)
			(drill 0.7112)
			(layers "*.Cu" "*.Mask")
			(remove_unused_layers no)
			(net "GND")
			(clearance 0.1016)
			(thermal_gap 0.1016)
		)
		(pad "B8" thru_hole circle
			(at -4.499864 6.999986 270)
			(size 1.016 1.016)
			(drill 0.7112)
			(layers "*.Cu" "*.Mask")
			(remove_unused_layers no)
			(net "GND")
			(clearance 0.1016)
			(thermal_gap 0.1016)
		)
		(pad "B9" thru_hole circle
			(at -2.499868 7.999984 270)
			(size 1.016 1.016)
			(drill 0.7112)
			(layers "*.Cu" "*.Mask")
			(remove_unused_layers no)
			(net "GND")
			(clearance 0.1016)
			(thermal_gap 0.1016)
		)
		(pad "B10" thru_hole circle
			(at -4.499864 8.999982 270)
			(size 1.016 1.016)
			(drill 0.7112)
			(layers "*.Cu" "*.Mask")
			(remove_unused_layers no)
			(net "I2C_PDB_SCL")
			(clearance 0.1016)
			(thermal_gap 0.1016)
		)
		(pad "B11" thru_hole circle
			(at -2.499868 9.99998 270)
			(size 1.016 1.016)
			(drill 0.7112)
			(layers "*.Cu" "*.Mask")
			(remove_unused_layers no)
			(net "I2C_PDB_SDA")
			(clearance 0.1016)
			(thermal_gap 0.1016)
		)
		(pad "B12" thru_hole circle
			(at -4.499864 12.999974 270)
			(size 1.016 1.016)
			(drill 0.7112)
			(layers "*.Cu" "*.Mask")
			(remove_unused_layers no)
			(net "P3V3")
			(clearance 0.1016)
			(thermal_gap 0.1016)
		)
		(pad "B13" thru_hole circle
			(at -2.499868 13.999972 270)
			(size 1.016 1.016)
			(drill 0.7112)
			(layers "*.Cu" "*.Mask")
			(remove_unused_layers no)
			(net "GND3")
			(clearance 0.1016)
			(thermal_gap 0.1016)
		)
		(pad "B14" thru_hole circle
			(at -4.499864 14.99997 270)
			(size 1.016 1.016)
			(drill 0.7112)
			(layers "*.Cu" "*.Mask")
			(remove_unused_layers no)
			(net "Net_442")
			(clearance 0.1016)
			(thermal_gap 0.1016)
		)
		(pad "B15" thru_hole circle
			(at -2.499868 15.999968 270)
			(size 1.016 1.016)
			(drill 0.7112)
			(layers "*.Cu" "*.Mask")
			(remove_unused_layers no)
			(net "Net_441")
			(clearance 0.1016)
			(thermal_gap 0.1016)
		)
		(pad "B16" thru_hole circle
			(at -4.499864 16.999966 270)
			(size 1.016 1.016)
			(drill 0.7112)
			(layers "*.Cu" "*.Mask")
			(remove_unused_layers no)
			(net "GND4")
			(clearance 0.1016)
			(thermal_gap 0.1016)
		)
		(pad "B17" thru_hole circle
			(at -2.499868 17.999964 270)
			(size 1.016 1.016)
			(drill 0.7112)
			(layers "*.Cu" "*.Mask")
			(remove_unused_layers no)
			(net "Net_440")
			(clearance 0.1016)
			(thermal_gap 0.1016)
		)
		(pad "B18" thru_hole circle
			(at -4.499864 18.999962 270)
			(size 1.016 1.016)
			(drill 0.7112)
			(layers "*.Cu" "*.Mask")
			(remove_unused_layers no)
			(net "GND")
			(clearance 0.1016)
			(thermal_gap 0.1016)
		)
		(pad "B19" thru_hole circle
			(at -2.499868 19.99996 270)
			(size 1.016 1.016)
			(drill 0.7112)
			(layers "*.Cu" "*.Mask")
			(remove_unused_layers no)
			(net "Net_3")
			(clearance 0.1016)
			(thermal_gap 0.1016)
		)
		(pad "B20" thru_hole circle
			(at -4.499864 20.999958 270)
			(size 1.016 1.016)
			(drill 0.7112)
			(layers "*.Cu" "*.Mask")
			(remove_unused_layers no)
			(net "Net_8")
			(clearance 0.1016)
			(thermal_gap 0.1016)
		)
		(pad "B21" thru_hole circle
			(at -2.499868 21.999956 270)
			(size 1.016 1.016)
			(drill 0.7112)
			(layers "*.Cu" "*.Mask")
			(remove_unused_layers no)
			(net "GND6")
			(clearance 0.1016)
			(thermal_gap 0.1016)
		)
		(pad "B22" thru_hole circle
			(at -4.499864 22.999954 270)
			(size 1.016 1.016)
			(drill 0.7112)
			(layers "*.Cu" "*.Mask")
			(remove_unused_layers no)
			(net "GND7")
			(clearance 0.1016)
			(thermal_gap 0.1016)
		)
		(pad "B23" thru_hole circle
			(at -2.499868 23.999952 270)
			(size 1.016 1.016)
			(drill 0.7112)
			(layers "*.Cu" "*.Mask")
			(remove_unused_layers no)
			(net "Net_2")
			(clearance 0.1016)
			(thermal_gap 0.1016)
		)
		(pad "B24" thru_hole circle
			(at -4.499864 24.99995 270)
			(size 1.016 1.016)
			(drill 0.7112)
			(layers "*.Cu" "*.Mask")
			(remove_unused_layers no)
			(net "Net_7")
			(clearance 0.1016)
			(thermal_gap 0.1016)
		)
		(pad "B25" thru_hole circle
			(at -2.499868 25.999948 270)
			(size 1.016 1.016)
			(drill 0.7112)
			(layers "*.Cu" "*.Mask")
			(remove_unused_layers no)
			(net "GND8")
			(clearance 0.1016)
			(thermal_gap 0.1016)
		)
		(pad "B26" thru_hole circle
			(at -4.499864 26.999946 270)
			(size 1.016 1.016)
			(drill 0.7112)
			(layers "*.Cu" "*.Mask")
			(remove_unused_layers no)
			(net "GND")
			(clearance 0.1016)
			(thermal_gap 0.1016)
		)
		(pad "B27" thru_hole circle
			(at -2.499868 27.999944 270)
			(size 1.016 1.016)
			(drill 0.7112)
			(layers "*.Cu" "*.Mask")
			(remove_unused_layers no)
			(net "FAN1_TACH")
			(clearance 0.1016)
			(thermal_gap 0.1016)
		)
		(pad "B28" thru_hole circle
			(at -4.499864 28.999942 270)
			(size 1.016 1.016)
			(drill 0.7112)
			(layers "*.Cu" "*.Mask")
			(remove_unused_layers no)
			(net "FAN2_TACH")
			(clearance 0.1016)
			(thermal_gap 0.1016)
		)
		(pad "B29" thru_hole circle
			(at -2.499868 29.99994 270)
			(size 1.016 1.016)
			(drill 0.7112)
			(layers "*.Cu" "*.Mask")
			(remove_unused_layers no)
			(net "FAN3_TACH")
			(clearance 0.1016)
			(thermal_gap 0.1016)
		)
		(pad "B30" thru_hole circle
			(at -4.499864 30.999938 270)
			(size 1.016 1.016)
			(drill 0.7112)
			(layers "*.Cu" "*.Mask")
			(remove_unused_layers no)
			(net "GND")
			(clearance 0.1016)
			(thermal_gap 0.1016)
		)
		(pad "B31" thru_hole circle
			(at -2.499868 31.999936 270)
			(size 1.016 1.016)
			(drill 0.7112)
			(layers "*.Cu" "*.Mask")
			(remove_unused_layers no)
			(net "T12_BLAD1_EN")
			(clearance 0.1016)
			(thermal_gap 0.1016)
		)
		(pad "B32" thru_hole circle
			(at -4.499864 32.999934 270)
			(size 1.016 1.016)
			(drill 0.7112)
			(layers "*.Cu" "*.Mask")
			(remove_unused_layers no)
			(net "TP_T12_BLAD2_EN")
			(clearance 0.1016)
			(thermal_gap 0.1016)
		)
		(pad "B33" thru_hole circle
			(at -2.499868 33.999932 270)
			(size 1.016 1.016)
			(drill 0.7112)
			(layers "*.Cu" "*.Mask")
			(remove_unused_layers no)
			(net "T12_BLAD3_EN")
			(clearance 0.1016)
			(thermal_gap 0.1016)
		)
		(pad "B34" thru_hole circle
			(at -4.499864 34.99993 270)
			(size 1.016 1.016)
			(drill 0.7112)
			(layers "*.Cu" "*.Mask")
			(remove_unused_layers no)
			(net "TP_T12_BLAD4_EN")
			(clearance 0.1016)
			(thermal_gap 0.1016)
		)
		(pad "B35" thru_hole circle
			(at -2.499868 35.999928 270)
			(size 1.016 1.016)
			(drill 0.7112)
			(layers "*.Cu" "*.Mask")
			(remove_unused_layers no)
			(net "GND")
			(clearance 0.1016)
			(thermal_gap 0.1016)
		)
		(pad "B36" thru_hole circle
			(at -4.499864 36.999926 270)
			(size 1.016 1.016)
			(drill 0.7112)
			(layers "*.Cu" "*.Mask")
			(remove_unused_layers no)
			(net "T12_BLAD1_RXD")
			(clearance 0.1016)
			(thermal_gap 0.1016)
		)
		(pad "B37" thru_hole circle
			(at -2.499868 37.999924 270)
			(size 1.016 1.016)
			(drill 0.7112)
			(layers "*.Cu" "*.Mask")
			(remove_unused_layers no)
			(net "T12_BLAD1_TXD")
			(clearance 0.1016)
			(thermal_gap 0.1016)
		)
		(pad "B38" thru_hole circle
			(at -4.499864 38.999922 270)
			(size 1.016 1.016)
			(drill 0.7112)
			(layers "*.Cu" "*.Mask")
			(remove_unused_layers no)
			(net "T12_BLAD2_RXD")
			(clearance 0.1016)
			(thermal_gap 0.1016)
		)
		(pad "B39" thru_hole circle
			(at -2.499868 39.99992 270)
			(size 1.016 1.016)
			(drill 0.7112)
			(layers "*.Cu" "*.Mask")
			(remove_unused_layers no)
			(net "T12_BLAD2_TXD")
			(clearance 0.1016)
			(thermal_gap 0.1016)
		)
		(pad "B40" thru_hole circle
			(at -4.499864 40.999918 270)
			(size 1.016 1.016)
			(drill 0.7112)
			(layers "*.Cu" "*.Mask")
			(remove_unused_layers no)
			(net "GND")
			(clearance 0.1016)
			(thermal_gap 0.1016)
		)
		(pad "B41" thru_hole circle
			(at -2.499868 41.999916 270)
			(size 1.016 1.016)
			(drill 0.7112)
			(layers "*.Cu" "*.Mask")
			(remove_unused_layers no)
			(net "T12_BLAD3_RXD")
			(clearance 0.1016)
			(thermal_gap 0.1016)
		)
		(pad "B42" thru_hole circle
			(at -4.499864 42.999914 270)
			(size 1.016 1.016)
			(drill 0.7112)
			(layers "*.Cu" "*.Mask")
			(remove_unused_layers no)
			(net "T12_BLAD3_TXD")
			(clearance 0.1016)
			(thermal_gap 0.1016)
		)
		(pad "B43" thru_hole circle
			(at -2.499868 43.999912 270)
			(size 1.016 1.016)
			(drill 0.7112)
			(layers "*.Cu" "*.Mask")
			(remove_unused_layers no)
			(net "T12_BLAD4_RXD")
			(clearance 0.1016)
			(thermal_gap 0.1016)
		)
		(pad "B44" thru_hole circle
			(at -4.499864 44.99991 270)
			(size 1.016 1.016)
			(drill 0.7112)
			(layers "*.Cu" "*.Mask")
			(remove_unused_layers no)
			(net "T12_BLAD4_TXD")
			(clearance 0.1016)
			(thermal_gap 0.1016)
		)
		(pad "B45" thru_hole circle
			(at -2.499868 45.999908 270)
			(size 1.016 1.016)
			(drill 0.7112)
			(layers "*.Cu" "*.Mask")
			(remove_unused_layers no)
			(net "GND")
			(clearance 0.1016)
			(thermal_gap 0.1016)
		)
		(pad "B46" thru_hole circle
			(at -4.499864 46.999906 270)
			(size 1.016 1.016)
			(drill 0.7112)
			(layers "*.Cu" "*.Mask")
			(remove_unused_layers no)
			(net "T10_BLAD1_EN")
			(clearance 0.1016)
			(thermal_gap 0.1016)
		)
		(pad "B47" thru_hole circle
			(at -2.499868 47.999904 270)
			(size 1.016 1.016)
			(drill 0.7112)
			(layers "*.Cu" "*.Mask")
			(remove_unused_layers no)
			(net "TP_T10_BLAD2_EN")
			(clearance 0.1016)
			(thermal_gap 0.1016)
		)
		(pad "B48" thru_hole circle
			(at -4.499864 48.999902 270)
			(size 1.016 1.016)
			(drill 0.7112)
			(layers "*.Cu" "*.Mask")
			(remove_unused_layers no)
			(net "T10_BLAD3_EN")
			(clearance 0.1016)
			(thermal_gap 0.1016)
		)
		(pad "B49" thru_hole circle
			(at -2.499868 49.9999 270)
			(size 1.016 1.016)
			(drill 0.7112)
			(layers "*.Cu" "*.Mask")
			(remove_unused_layers no)
			(net "TP_T10_BLAD4_EN")
			(clearance 0.1016)
			(thermal_gap 0.1016)
		)
		(pad "B50" thru_hole circle
			(at -4.499864 50.999898 270)
			(size 1.016 1.016)
			(drill 0.7112)
			(layers "*.Cu" "*.Mask")
			(remove_unused_layers no)
			(net "GND")
			(clearance 0.1016)
			(thermal_gap 0.1016)
		)
		(pad "B51" thru_hole circle
			(at -2.499868 51.999896 270)
			(size 1.016 1.016)
			(drill 0.7112)
			(layers "*.Cu" "*.Mask")
			(remove_unused_layers no)
			(net "T10_BLAD1_RXD")
			(clearance 0.1016)
			(thermal_gap 0.1016)
		)
		(pad "B52" thru_hole circle
			(at -4.499864 52.999894 270)
			(size 1.016 1.016)
			(drill 0.7112)
			(layers "*.Cu" "*.Mask")
			(remove_unused_layers no)
			(net "T10_BLAD1_TXD")
			(clearance 0.1016)
			(thermal_gap 0.1016)
		)
		(pad "B53" thru_hole circle
			(at -2.499868 53.999892 270)
			(size 1.016 1.016)
			(drill 0.7112)
			(layers "*.Cu" "*.Mask")
			(remove_unused_layers no)
			(net "T10_BLAD2_RXD")
			(clearance 0.1016)
			(thermal_gap 0.1016)
		)
		(pad "B54" thru_hole circle
			(at -4.499864 54.99989 270)
			(size 1.016 1.016)
			(drill 0.7112)
			(layers "*.Cu" "*.Mask")
			(remove_unused_layers no)
			(net "T10_BLAD2_TXD")
			(clearance 0.1016)
			(thermal_gap 0.1016)
		)
		(pad "B55" thru_hole circle
			(at -2.499868 55.999888 270)
			(size 1.016 1.016)
			(drill 0.7112)
			(layers "*.Cu" "*.Mask")
			(remove_unused_layers no)
			(net "GND")
			(clearance 0.1016)
			(thermal_gap 0.1016)
		)
		(pad "B56" thru_hole circle
			(at -4.499864 56.999886 270)
			(size 1.016 1.016)
			(drill 0.7112)
			(layers "*.Cu" "*.Mask")
			(remove_unused_layers no)
			(net "T10_BLAD3_RXD")
			(clearance 0.1016)
			(thermal_gap 0.1016)
		)
		(pad "B57" thru_hole circle
			(at -2.499868 57.999884 270)
			(size 1.016 1.016)
			(drill 0.7112)
			(layers "*.Cu" "*.Mask")
			(remove_unused_layers no)
			(net "T10_BLAD3_TXD")
			(clearance 0.1016)
			(thermal_gap 0.1016)
		)
		(pad "B58" thru_hole circle
			(at -4.499864 59.000136 270)
			(size 1.016 1.016)
			(drill 0.7112)
			(layers "*.Cu" "*.Mask")
			(remove_unused_layers no)
			(net "T10_BLAD4_RXD")
			(clearance 0.1016)
			(thermal_gap 0.1016)
		)
		(pad "B59" thru_hole circle
			(at -2.499868 59.99988 270)
			(size 1.016 1.016)
			(drill 0.7112)
			(layers "*.Cu" "*.Mask")
			(remove_unused_layers no)
			(net "T10_BLAD4_TXD")
			(clearance 0.1016)
			(thermal_gap 0.1016)
		)
		(pad "B60" thru_hole circle
			(at -4.499864 61.000132 270)
			(size 1.016 1.016)
			(drill 0.7112)
			(layers "*.Cu" "*.Mask")
			(remove_unused_layers no)
			(net "GND")
			(clearance 0.1016)
			(thermal_gap 0.1016)
		)
		(pad "B61" thru_hole circle
			(at -2.499868 61.999876 270)
			(size 1.016 1.016)
			(drill 0.7112)
			(layers "*.Cu" "*.Mask")
			(remove_unused_layers no)
			(net "T8_BLAD1_EN")
			(clearance 0.1016)
			(thermal_gap 0.1016)
		)
		(pad "B62" thru_hole circle
			(at -4.499864 63.000128 270)
			(size 1.016 1.016)
			(drill 0.7112)
			(layers "*.Cu" "*.Mask")
			(remove_unused_layers no)
			(net "TP_T8_BLAD2_EN")
			(clearance 0.1016)
			(thermal_gap 0.1016)
		)
		(pad "B63" thru_hole circle
			(at -2.499868 63.999872 270)
			(size 1.016 1.016)
			(drill 0.7112)
			(layers "*.Cu" "*.Mask")
			(remove_unused_layers no)
			(net "T8_BLAD3_EN")
			(clearance 0.1016)
			(thermal_gap 0.1016)
		)
		(pad "B64" thru_hole circle
			(at -4.499864 65.000124 270)
			(size 1.016 1.016)
			(drill 0.7112)
			(layers "*.Cu" "*.Mask")
			(remove_unused_layers no)
			(net "TP_T8_BLAD4_EN")
			(clearance 0.1016)
			(thermal_gap 0.1016)
		)
		(pad "B65" thru_hole circle
			(at -2.499868 65.999868 270)
			(size 1.016 1.016)
			(drill 0.7112)
			(layers "*.Cu" "*.Mask")
			(remove_unused_layers no)
			(net "GND")
			(clearance 0.1016)
			(thermal_gap 0.1016)
		)
		(pad "B66" thru_hole circle
			(at -4.499864 67.00012 270)
			(size 1.016 1.016)
			(drill 0.7112)
			(layers "*.Cu" "*.Mask")
			(remove_unused_layers no)
			(net "T8_BLAD1_RXD")
			(clearance 0.1016)
			(thermal_gap 0.1016)
		)
		(pad "B67" thru_hole circle
			(at -2.499868 67.999864 270)
			(size 1.016 1.016)
			(drill 0.7112)
			(layers "*.Cu" "*.Mask")
			(remove_unused_layers no)
			(net "T8_BLAD1_TXD")
			(clearance 0.1016)
			(thermal_gap 0.1016)
		)
		(pad "B68" thru_hole circle
			(at -4.499864 69.000116 270)
			(size 1.016 1.016)
			(drill 0.7112)
			(layers "*.Cu" "*.Mask")
			(remove_unused_layers no)
			(net "T8_BLAD2_RXD")
			(clearance 0.1016)
			(thermal_gap 0.1016)
		)
		(pad "B69" thru_hole circle
			(at -2.499868 70.000114 270)
			(size 1.016 1.016)
			(drill 0.7112)
			(layers "*.Cu" "*.Mask")
			(remove_unused_layers no)
			(net "T8_BLAD2_TXD")
			(clearance 0.1016)
			(thermal_gap 0.1016)
		)
		(pad "B70" thru_hole circle
			(at -4.499864 71.000112 270)
			(size 1.016 1.016)
			(drill 0.7112)
			(layers "*.Cu" "*.Mask")
			(remove_unused_layers no)
			(net "GND")
			(clearance 0.1016)
			(thermal_gap 0.1016)
		)
		(pad "B71" thru_hole circle
			(at -2.499868 72.00011 270)
			(size 1.016 1.016)
			(drill 0.7112)
			(layers "*.Cu" "*.Mask")
			(remove_unused_layers no)
			(net "T8_BLAD3_RXD")
			(clearance 0.1016)
			(thermal_gap 0.1016)
		)
		(pad "B72" thru_hole circle
			(at -4.499864 73.000108 270)
			(size 1.016 1.016)
			(drill 0.7112)
			(layers "*.Cu" "*.Mask")
			(remove_unused_layers no)
			(net "T8_BLAD3_TXD")
			(clearance 0.1016)
			(thermal_gap 0.1016)
		)
	)
)
